(kicad_pcb
	(version 20260206)
	(generator "pcbnew")
	(generator_version "10.0")
	(general
		(thickness 1.6)
		(legacy_teardrops no)
	)
	(paper "A4")
	(title_block
		(title "12092022_DA0F0TYB4D0_F0T_Panel_BD_Front_D_brd_v02_OCP.brd")
		(comment 1 "Grand Teton / footprints 57-63 of 128")
	)
	(layers
		(0 "F.Cu" signal "TOP")
		(4 "In1.Cu" signal "GND")
		(6 "In2.Cu" signal "GND1")
		(2 "B.Cu" signal "BOTTOM")
		(9 "F.Adhes" user "F.Adhesive")
		(11 "B.Adhes" user "B.Adhesive")
		(13 "F.Paste" user "Package Geometry/Pastemask Top")
		(15 "B.Paste" user "Package Geometry/Pastemask Bottom")
		(5 "F.SilkS" user "Ref Des/Silkscreen Top")
		(7 "B.SilkS" user "Ref Des/Silkscreen Bottom")
		(1 "F.Mask" user "Board Geometry/Soldermask Top")
		(3 "B.Mask" user "Board Geometry/Soldermask Bottom")
		(17 "Dwgs.User" user "User.Drawings")
		(19 "Cmts.User" user "User.Comments")
		(21 "Eco1.User" user "User.Eco1")
		(23 "Eco2.User" user "User.Eco2")
		(25 "Edge.Cuts" user "Board Geometry/Outline")
		(27 "Margin" user)
		(31 "F.CrtYd" user "Package Geometry/Place Bound Top")
		(29 "B.CrtYd" user "Package Geometry/Place Bound Bottom")
		(35 "F.Fab" user "Ref Des/Assembly Top")
		(33 "B.Fab" user "Ref Des/Assembly Bottom")
	)
	(footprint ""
		(layer "F.Cu")
		(at 18.923 -19.431 -90)
		(property "Reference" "U11"
			(at -0.508 -1.93167 90)
			(unlocked yes)
			(layer "F.SilkS")
			(effects
				(font
					(size 0.7874 0.5842)
					(thickness 0.1524)
				)
				(justify left)
			)
		)
		(property "Value" ""
			(at 0 0 270)
			(layer "F.Fab")
			(effects
				(font
					(size 1.27 1.27)
				)
			)
		)
		(duplicate_pad_numbers_are_jumpers no)
		(fp_line
			(start -0.517398 1.500124)
			(end -0.517398 -1.500124)
			(stroke
				(width 0.1524)
				(type default)
			)
			(layer "F.SilkS")
		)
		(fp_line
			(start 0.517398 1.500124)
			(end -0.517398 1.500124)
			(stroke
				(width 0.1524)
				(type default)
			)
			(layer "F.SilkS")
		)
		(fp_line
			(start -0.517398 -1.500124)
			(end 0.517398 -1.500124)
			(stroke
				(width 0.1524)
				(type default)
			)
			(layer "F.SilkS")
		)
		(fp_line
			(start 0.517398 -1.500124)
			(end 0.517398 1.500124)
			(stroke
				(width 0.1524)
				(type default)
			)
			(layer "F.SilkS")
		)
		(fp_poly
			(pts
				(xy -1.5113 -0.750062) (xy -2.1463 -1.067562) (xy -2.1463 -0.432562)
			)
			(stroke
				(width 0)
				(type default)
			)
			(fill yes)
			(layer "F.SilkS")
		)
		(fp_line
			(start -0.700024 1.500124)
			(end -0.700024 -1.500124)
			(stroke
				(width 0.1)
				(type default)
			)
			(layer "F.Fab")
		)
		(fp_line
			(start 0.700024 1.500124)
			(end -0.700024 1.500124)
			(stroke
				(width 0.1)
				(type default)
			)
			(layer "F.Fab")
		)
		(fp_line
			(start -0.700024 -1.500124)
			(end 0.700024 -1.500124)
			(stroke
				(width 0.1)
				(type default)
			)
			(layer "F.Fab")
		)
		(fp_line
			(start 0.700024 -1.500124)
			(end 0.700024 1.500124)
			(stroke
				(width 0.1)
				(type default)
			)
			(layer "F.Fab")
		)
		(fp_poly
			(pts
				(xy -1.5113 -0.750062) (xy -2.1463 -1.067562) (xy -2.1463 -0.432562)
			)
			(stroke
				(width 0)
				(type default)
			)
			(fill yes)
			(layer "F.Fab")
		)
		(pad "1" smd rect
			(at -0.999998 -0.750062 270)
			(size 0.7112 1.016)
			(layers "F.Cu" "F.Mask" "F.Paste")
			(net "GND")
		)
		(pad "2" smd rect
			(at -0.999998 0.94996 180)
			(size 0.6096 0.7112)
			(layers "F.Cu" "F.Mask" "F.Paste")
			(net "SMB_IO_DEBUG_CARD_SCL")
		)
		(pad "3" smd rect
			(at 0.999998 0.94996 180)
			(size 0.6096 0.7112)
			(layers "F.Cu" "F.Mask" "F.Paste")
			(net "SMB_IO_DEBUG_CARD_SDA")
		)
		(pad "4" smd rect
			(at 0.999998 -0.94996 180)
			(size 0.6096 0.7112)
			(layers "F.Cu" "F.Mask" "F.Paste")
			(net "P5V_STBY_DEBUG")
		)
	)
	(footprint ""
		(layer "F.Cu")
		(at 17.526 -22.098 180)
		(property "Reference" "R47"
			(at 0.127 4.16433 0)
			(unlocked yes)
			(layer "F.SilkS")
			(effects
				(font
					(size 0.7874 0.5842)
					(thickness 0.1524)
				)
			)
		)
		(property "Value" ""
			(at 0 0 180)
			(layer "F.Fab")
			(effects
				(font
					(size 1.27 1.27)
				)
			)
		)
		(duplicate_pad_numbers_are_jumpers no)
		(fp_line
			(start 0.7874 0.4064)
			(end -0.7874 0.4064)
			(stroke
				(width 0.1524)
				(type default)
			)
			(layer "F.SilkS")
		)
		(fp_line
			(start 0.7874 -0.4064)
			(end 0.7874 0.4064)
			(stroke
				(width 0.1524)
				(type default)
			)
			(layer "F.SilkS")
		)
		(fp_line
			(start -0.7874 0.4064)
			(end -0.7874 -0.4064)
			(stroke
				(width 0.1524)
				(type default)
			)
			(layer "F.SilkS")
		)
		(fp_line
			(start -0.7874 -0.4064)
			(end 0.7874 -0.4064)
			(stroke
				(width 0.1524)
				(type default)
			)
			(layer "F.SilkS")
		)
		(fp_line
			(start 0.67945 0.3048)
			(end 0.120396 0.3048)
			(stroke
				(width 0.1)
				(type default)
			)
			(layer "F.Fab")
		)
		(fp_line
			(start 0.67945 -0.3048)
			(end 0.67945 0.3048)
			(stroke
				(width 0.1)
				(type default)
			)
			(layer "F.Fab")
		)
		(fp_line
			(start 0.12065 -0.2794)
			(end 0.12065 -0.3048)
			(stroke
				(width 0.1)
				(type default)
			)
			(layer "F.Fab")
		)
		(fp_line
			(start 0.12065 -0.3048)
			(end 0.67945 -0.3048)
			(stroke
				(width 0.1)
				(type default)
			)
			(layer "F.Fab")
		)
		(fp_line
			(start 0.120396 0.3048)
			(end 0.120396 0.2794)
			(stroke
				(width 0.1)
				(type default)
			)
			(layer "F.Fab")
		)
		(fp_line
			(start 0.120396 0.2794)
			(end -0.12065 0.2794)
			(stroke
				(width 0.1)
				(type default)
			)
			(layer "F.Fab")
		)
		(fp_line
			(start -0.12065 0.3048)
			(end -0.67945 0.3048)
			(stroke
				(width 0.1)
				(type default)
			)
			(layer "F.Fab")
		)
		(fp_line
			(start -0.12065 0.2794)
			(end -0.12065 0.3048)
			(stroke
				(width 0.1)
				(type default)
			)
			(layer "F.Fab")
		)
		(fp_line
			(start -0.12065 -0.2794)
			(end 0.12065 -0.2794)
			(stroke
				(width 0.1)
				(type default)
			)
			(layer "F.Fab")
		)
		(fp_line
			(start -0.12065 -0.305054)
			(end -0.12065 -0.2794)
			(stroke
				(width 0.1)
				(type default)
			)
			(layer "F.Fab")
		)
		(fp_line
			(start -0.67945 0.3048)
			(end -0.67945 -0.305054)
			(stroke
				(width 0.1)
				(type default)
			)
			(layer "F.Fab")
		)
		(fp_line
			(start -0.67945 -0.305054)
			(end -0.12065 -0.305054)
			(stroke
				(width 0.1)
				(type default)
			)
			(layer "F.Fab")
		)
		(pad "1" smd circle
			(at -0.40005 0 180)
			(size 0 0)
			(layers "F.Cu" "F.Mask" "F.Paste")
			(net "P3V3_STBY")
		)
		(pad "2" smd circle
			(at 0.40005 0 180)
			(size 0 0)
			(layers "F.Cu" "F.Mask" "F.Paste")
			(net "SMB_IO_DEBUG_CARD_SCL")
		)
	)
	(footprint ""
		(layer "F.Cu")
		(at 5.969 -53.213)
		(property "Reference" "R21"
			(at -2.794 0.40767 0)
			(unlocked yes)
			(layer "F.SilkS")
			(effects
				(font
					(size 0.7874 0.5842)
					(thickness 0.1524)
				)
			)
		)
		(property "Value" ""
			(at 0 0 0)
			(layer "F.Fab")
			(effects
				(font
					(size 1.27 1.27)
				)
			)
		)
		(duplicate_pad_numbers_are_jumpers no)
		(fp_line
			(start -0.7874 -0.4064)
			(end 0.7874 -0.4064)
			(stroke
				(width 0.1524)
				(type default)
			)
			(layer "F.SilkS")
		)
		(fp_line
			(start -0.7874 0.4064)
			(end -0.7874 -0.4064)
			(stroke
				(width 0.1524)
				(type default)
			)
			(layer "F.SilkS")
		)
		(fp_line
			(start 0.7874 -0.4064)
			(end 0.7874 0.4064)
			(stroke
				(width 0.1524)
				(type default)
			)
			(layer "F.SilkS")
		)
		(fp_line
			(start 0.7874 0.4064)
			(end -0.7874 0.4064)
			(stroke
				(width 0.1524)
				(type default)
			)
			(layer "F.SilkS")
		)
		(fp_line
			(start -0.67945 -0.305054)
			(end -0.12065 -0.305054)
			(stroke
				(width 0.1)
				(type default)
			)
			(layer "F.Fab")
		)
		(fp_line
			(start -0.67945 0.3048)
			(end -0.67945 -0.305054)
			(stroke
				(width 0.1)
				(type default)
			)
			(layer "F.Fab")
		)
		(fp_line
			(start -0.12065 -0.305054)
			(end -0.12065 -0.2794)
			(stroke
				(width 0.1)
				(type default)
			)
			(layer "F.Fab")
		)
		(fp_line
			(start -0.12065 -0.2794)
			(end 0.12065 -0.2794)
			(stroke
				(width 0.1)
				(type default)
			)
			(layer "F.Fab")
		)
		(fp_line
			(start -0.12065 0.2794)
			(end -0.12065 0.3048)
			(stroke
				(width 0.1)
				(type default)
			)
			(layer "F.Fab")
		)
		(fp_line
			(start -0.12065 0.3048)
			(end -0.67945 0.3048)
			(stroke
				(width 0.1)
				(type default)
			)
			(layer "F.Fab")
		)
		(fp_line
			(start 0.120396 0.2794)
			(end -0.12065 0.2794)
			(stroke
				(width 0.1)
				(type default)
			)
			(layer "F.Fab")
		)
		(fp_line
			(start 0.120396 0.3048)
			(end 0.120396 0.2794)
			(stroke
				(width 0.1)
				(type default)
			)
			(layer "F.Fab")
		)
		(fp_line
			(start 0.12065 -0.3048)
			(end 0.67945 -0.3048)
			(stroke
				(width 0.1)
				(type default)
			)
			(layer "F.Fab")
		)
		(fp_line
			(start 0.12065 -0.2794)
			(end 0.12065 -0.3048)
			(stroke
				(width 0.1)
				(type default)
			)
			(layer "F.Fab")
		)
		(fp_line
			(start 0.67945 -0.3048)
			(end 0.67945 0.3048)
			(stroke
				(width 0.1)
				(type default)
			)
			(layer "F.Fab")
		)
		(fp_line
			(start 0.67945 0.3048)
			(end 0.120396 0.3048)
			(stroke
				(width 0.1)
				(type default)
			)
			(layer "F.Fab")
		)
		(pad "1" smd circle
			(at -0.40005 0)
			(size 0 0)
			(layers "F.Cu" "F.Mask" "F.Paste")
			(net "P3V3_STBY")
		)
		(pad "2" smd circle
			(at 0.40005 0)
			(size 0 0)
			(layers "F.Cu" "F.Mask" "F.Paste")
			(net "REV_ID<0>")
		)
	)
	(footprint ""
		(layer "F.Cu")
		(at 10.033 -27.813)
		(property "Reference" "R11"
			(at -0.254 -2.38633 0)
			(unlocked yes)
			(layer "F.SilkS")
			(effects
				(font
					(size 0.7874 0.5842)
					(thickness 0.1524)
				)
			)
		)
		(property "Value" ""
			(at 0 0 0)
			(layer "F.Fab")
			(effects
				(font
					(size 1.27 1.27)
				)
			)
		)
		(duplicate_pad_numbers_are_jumpers no)
		(fp_line
			(start -1.2954 -0.5842)
			(end 1.2954 -0.5842)
			(stroke
				(width 0.1524)
				(type default)
			)
			(layer "F.SilkS")
		)
		(fp_line
			(start -1.2954 0.5842)
			(end -1.2954 -0.5842)
			(stroke
				(width 0.1524)
				(type default)
			)
			(layer "F.SilkS")
		)
		(fp_line
			(start 1.2954 -0.5842)
			(end 1.2954 0.5842)
			(stroke
				(width 0.1524)
				(type default)
			)
			(layer "F.SilkS")
		)
		(fp_line
			(start 1.2954 0.5842)
			(end -1.2954 0.5842)
			(stroke
				(width 0.1524)
				(type default)
			)
			(layer "F.SilkS")
		)
		(fp_line
			(start -1.1938 -0.406654)
			(end -0.8636 -0.406654)
			(stroke
				(width 0.1)
				(type default)
			)
			(layer "F.Fab")
		)
		(fp_line
			(start -1.1938 0.4064)
			(end -1.1938 -0.406654)
			(stroke
				(width 0.1)
				(type default)
			)
			(layer "F.Fab")
		)
		(fp_line
			(start -0.8636 -0.4572)
			(end 0.8636 -0.4572)
			(stroke
				(width 0.1)
				(type default)
			)
			(layer "F.Fab")
		)
		(fp_line
			(start -0.8636 -0.406654)
			(end -0.8636 -0.4572)
			(stroke
				(width 0.1)
				(type default)
			)
			(layer "F.Fab")
		)
		(fp_line
			(start -0.8636 0.4064)
			(end -1.1938 0.4064)
			(stroke
				(width 0.1)
				(type default)
			)
			(layer "F.Fab")
		)
		(fp_line
			(start -0.8636 0.4318)
			(end -0.8636 0.4064)
			(stroke
				(width 0.1)
				(type default)
			)
			(layer "F.Fab")
		)
		(fp_line
			(start -0.8636 0.4572)
			(end -0.8636 0.4318)
			(stroke
				(width 0.1)
				(type default)
			)
			(layer "F.Fab")
		)
		(fp_line
			(start 0.8636 -0.4572)
			(end 0.8636 -0.406654)
			(stroke
				(width 0.1)
				(type default)
			)
			(layer "F.Fab")
		)
		(fp_line
			(start 0.8636 -0.406654)
			(end 1.1938 -0.406654)
			(stroke
				(width 0.1)
				(type default)
			)
			(layer "F.Fab")
		)
		(fp_line
			(start 0.8636 0.4064)
			(end 0.8636 0.4572)
			(stroke
				(width 0.1)
				(type default)
			)
			(layer "F.Fab")
		)
		(fp_line
			(start 0.8636 0.4572)
			(end -0.8636 0.4572)
			(stroke
				(width 0.1)
				(type default)
			)
			(layer "F.Fab")
		)
		(fp_line
			(start 1.1938 -0.406654)
			(end 1.1938 0.4064)
			(stroke
				(width 0.1)
				(type default)
			)
			(layer "F.Fab")
		)
		(fp_line
			(start 1.1938 0.4064)
			(end 0.8636 0.4064)
			(stroke
				(width 0.1)
				(type default)
			)
			(layer "F.Fab")
		)
		(pad "1" smd rect
			(at -0.7366 0 270)
			(size 0.7112 0.8128)
			(layers "F.Cu" "F.Mask" "F.Paste")
			(net "PWR_LED_R1_N")
		)
		(pad "2" smd rect
			(at 0.7366 0 270)
			(size 0.7112 0.8128)
			(layers "F.Cu" "F.Mask" "F.Paste")
			(net "PWR_LED_R2_N")
		)
	)
	(footprint ""
		(layer "F.Cu")
		(at 31.609792 -23.855934)
		(property "Reference" "L1"
			(at -2.145792 1.784604 0)
			(unlocked yes)
			(layer "F.SilkS")
			(effects
				(font
					(size 0.7874 0.5842)
					(thickness 0.1524)
				)
				(justify left)
			)
		)
		(property "Value" ""
			(at 0 0 0)
			(layer "F.Fab")
			(effects
				(font
					(size 1.27 1.27)
				)
			)
		)
		(duplicate_pad_numbers_are_jumpers no)
		(fp_line
			(start -0.8636 -1.524)
			(end 0.8636 -1.524)
			(stroke
				(width 0.1524)
				(type default)
			)
			(layer "F.SilkS")
		)
		(fp_line
			(start -0.8636 1.524)
			(end -0.8636 -1.524)
			(stroke
				(width 0.1524)
				(type default)
			)
			(layer "F.SilkS")
		)
		(fp_line
			(start 0.8636 -1.524)
			(end 0.8636 1.524)
			(stroke
				(width 0.1524)
				(type default)
			)
			(layer "F.SilkS")
		)
		(fp_line
			(start 0.8636 1.524)
			(end -0.8636 1.524)
			(stroke
				(width 0.1524)
				(type default)
			)
			(layer "F.SilkS")
		)
		(fp_poly
			(pts
				(xy -1.11633 -1.448816) (xy -1.62433 -1.194816) (xy -1.62433 -1.702816)
			)
			(stroke
				(width 0)
				(type default)
			)
			(fill yes)
			(layer "F.SilkS")
		)
		(fp_line
			(start -0.700024 -1.100074)
			(end 0.700024 -1.100074)
			(stroke
				(width 0.1)
				(type default)
			)
			(layer "F.Fab")
		)
		(fp_line
			(start -0.700024 1.100074)
			(end -0.700024 -1.100074)
			(stroke
				(width 0.1)
				(type default)
			)
			(layer "F.Fab")
		)
		(fp_line
			(start 0.700024 -1.100074)
			(end 0.700024 1.100074)
			(stroke
				(width 0.1)
				(type default)
			)
			(layer "F.Fab")
		)
		(fp_line
			(start 0.700024 1.100074)
			(end -0.700024 1.100074)
			(stroke
				(width 0.1)
				(type default)
			)
			(layer "F.Fab")
		)
		(fp_poly
			(pts
				(xy -0.4572 -1.6256) (xy -0.7112 -2.1336) (xy -0.2032 -2.1336)
			)
			(stroke
				(width 0)
				(type default)
			)
			(fill yes)
			(layer "F.Fab")
		)
		(pad "1" smd rect
			(at -0.424942 -0.849884)
			(size 0.3556 0.9144)
			(layers "F.Cu" "F.Mask" "F.Paste")
			(net "USB2_DN")
		)
		(pad "2" smd rect
			(at -0.424942 0.849884)
			(size 0.3556 0.9144)
			(layers "F.Cu" "F.Mask" "F.Paste")
			(net "USB2_DEBUG_DN")
		)
		(pad "3" smd rect
			(at 0.424942 0.849884)
			(size 0.3556 0.9144)
			(layers "F.Cu" "F.Mask" "F.Paste")
			(net "USB2_DEBUG_DP")
		)
		(pad "4" smd rect
			(at 0.424942 -0.849884)
			(size 0.3556 0.9144)
			(layers "F.Cu" "F.Mask" "F.Paste")
			(net "USB2_DP")
		)
	)
	(footprint ""
		(layer "F.Cu")
		(at 2.918206 -21.814282)
		(property "Reference" ""
			(at 0 0 0)
			(layer "F.SilkS")
			(hide yes)
			(effects
				(font
					(size 1.27 1.27)
				)
			)
		)
		(property "Value" ""
			(at 0 0 0)
			(layer "F.Fab")
			(effects
				(font
					(size 1.27 1.27)
				)
			)
		)
		(duplicate_pad_numbers_are_jumpers no)
		(pad "1" smd circle
			(at 0 0)
			(size 0.9906 0.9906)
			(layers "F.Cu" "F.Mask" "F.Paste")
			(net "Net_12")
		)
		(zone
			(layer "F.Cu")
			(hatch none 0.5)
			(connect_pads
				(clearance 0)
			)
			(min_thickness 0.25)
			(keepout
				(tracks not_allowed)
				(vias allowed)
				(pads allowed)
				(copperpour not_allowed)
				(footprints allowed)
			)
			(placement
				(enabled no)
				(sheetname "")
			)
			(fill
				(thermal_gap 0.5)
				(thermal_bridge_width 0.5)
				(island_removal_mode 0)
			)
			(polygon
				(pts
					(arc
						(start 4.543806 -21.814282)
						(mid 1.292606 -21.814282)
						(end 4.543806 -21.814282)
					)
				)
			)
		)
	)
	(footprint ""
		(layer "F.Cu")
		(at 5.969 -59.309 180)
		(property "Reference" "R18"
			(at 2.794 -0.40767 0)
			(unlocked yes)
			(layer "F.SilkS")
			(effects
				(font
					(size 0.7874 0.5842)
					(thickness 0.1524)
				)
			)
		)
		(property "Value" ""
			(at 0 0 180)
			(layer "F.Fab")
			(effects
				(font
					(size 1.27 1.27)
				)
			)
		)
		(duplicate_pad_numbers_are_jumpers no)
		(fp_line
			(start 0.7874 0.4064)
			(end -0.7874 0.4064)
			(stroke
				(width 0.1524)
				(type default)
			)
			(layer "F.SilkS")
		)
		(fp_line
			(start 0.7874 -0.4064)
			(end 0.7874 0.4064)
			(stroke
				(width 0.1524)
				(type default)
			)
			(layer "F.SilkS")
		)
		(fp_line
			(start -0.7874 0.4064)
			(end -0.7874 -0.4064)
			(stroke
				(width 0.1524)
				(type default)
			)
			(layer "F.SilkS")
		)
		(fp_line
			(start -0.7874 -0.4064)
			(end 0.7874 -0.4064)
			(stroke
				(width 0.1524)
				(type default)
			)
			(layer "F.SilkS")
		)
		(fp_line
			(start 0.67945 0.3048)
			(end 0.120396 0.3048)
			(stroke
				(width 0.1)
				(type default)
			)
			(layer "F.Fab")
		)
		(fp_line
			(start 0.67945 -0.3048)
			(end 0.67945 0.3048)
			(stroke
				(width 0.1)
				(type default)
			)
			(layer "F.Fab")
		)
		(fp_line
			(start 0.12065 -0.2794)
			(end 0.12065 -0.3048)
			(stroke
				(width 0.1)
				(type default)
			)
			(layer "F.Fab")
		)
		(fp_line
			(start 0.12065 -0.3048)
			(end 0.67945 -0.3048)
			(stroke
				(width 0.1)
				(type default)
			)
			(layer "F.Fab")
		)
		(fp_line
			(start 0.120396 0.3048)
			(end 0.120396 0.2794)
			(stroke
				(width 0.1)
				(type default)
			)
			(layer "F.Fab")
		)
		(fp_line
			(start 0.120396 0.2794)
			(end -0.12065 0.2794)
			(stroke
				(width 0.1)
				(type default)
			)
			(layer "F.Fab")
		)
		(fp_line
			(start -0.12065 0.3048)
			(end -0.67945 0.3048)
			(stroke
				(width 0.1)
				(type default)
			)
			(layer "F.Fab")
		)
		(fp_line
			(start -0.12065 0.2794)
			(end -0.12065 0.3048)
			(stroke
				(width 0.1)
				(type default)
			)
			(layer "F.Fab")
		)
		(fp_line
			(start -0.12065 -0.2794)
			(end 0.12065 -0.2794)
			(stroke
				(width 0.1)
				(type default)
			)
			(layer "F.Fab")
		)
		(fp_line
			(start -0.12065 -0.305054)
			(end -0.12065 -0.2794)
			(stroke
				(width 0.1)
				(type default)
			)
			(layer "F.Fab")
		)
		(fp_line
			(start -0.67945 0.3048)
			(end -0.67945 -0.305054)
			(stroke
				(width 0.1)
				(type default)
			)
			(layer "F.Fab")
		)
		(fp_line
			(start -0.67945 -0.305054)
			(end -0.12065 -0.305054)
			(stroke
				(width 0.1)
				(type default)
			)
			(layer "F.Fab")
		)
		(pad "1" smd circle
			(at -0.40005 0 180)
			(size 0 0)
			(layers "F.Cu" "F.Mask" "F.Paste")
			(net "RST_SMB_R_N")
		)
		(pad "2" smd circle
			(at 0.40005 0 180)
			(size 0 0)
			(layers "F.Cu" "F.Mask" "F.Paste")
			(net "P3V3_STBY")
		)
	)
)
